# TIMECARD (Time Appliance Project (Time Card)) — schematic netlist excerpt (pin names and nets, part order shuffled) for the footprints in the layout excerpt that follows; sources: Cadence DE-HDL packaged netlist, KiCad conversion of R4006-B0001-02_R01.brd

R399  RESISTOR  33OHM 1%  pkg SMC_0402R_H016  page 26 : \1\ = GPS_SMA_LED_RED_N ; \2\ = UNNAMED_14_LED4PV14_I269_3

(kicad_pcb
	(version 20260206)
	(generator "pcbnew")
	(generator_version "10.0")
	(general
		(thickness 1.6)
		(legacy_teardrops no)
	)
	(paper "A4")
	(title_block
		(title "timecard-production-celestica-r4006 — R4006-B0001-02_R01.brd")
		(comment 1 "Time Appliance Project (Time Card) / footprints 132-132 of 1113")
	)
	(layers
		(0 "F.Cu" signal "TOP")
		(4 "In1.Cu" signal "L02_GND1")
		(6 "In2.Cu" signal "L03_SIG1")
		(8 "In3.Cu" signal "L04_GND2")
		(10 "In4.Cu" signal "L05_VCC1")
		(12 "In5.Cu" signal "L06_VCC2")
		(14 "In6.Cu" signal "L07_GND3")
		(16 "In7.Cu" signal "L08_SIG2")
		(18 "In8.Cu" signal "L09_GND4")
		(2 "B.Cu" signal "BOTTOM")
		(9 "F.Adhes" user "F.Adhesive")
		(11 "B.Adhes" user "B.Adhesive")
		(13 "F.Paste" user "Package Geometry/Pastemask Top")
		(15 "B.Paste" user "Package Geometry/Pastemask Bottom")
		(5 "F.SilkS" user "Ref Des/Silkscreen Top")
		(7 "B.SilkS" user "Ref Des/Silkscreen Bottom")
		(1 "F.Mask" user "Board Geometry/Soldermask Top")
		(3 "B.Mask" user "Board Geometry/Soldermask Bottom")
		(17 "Dwgs.User" user "User.Drawings")
		(19 "Cmts.User" user "User.Comments")
		(21 "Eco1.User" user "User.Eco1")
		(23 "Eco2.User" user "User.Eco2")
		(25 "Edge.Cuts" user "Board Geometry/Outline")
		(27 "Margin" user)
		(31 "F.CrtYd" user "Package Geometry/Place Bound Top")
		(29 "B.CrtYd" user "Package Geometry/Place Bound Bottom")
		(35 "F.Fab" user "Ref Des/Assembly Top")
		(33 "B.Fab" user "Ref Des/Assembly Bottom")
	)
	(footprint ""
		(layer "F.Cu")
		(at 8.382 -81.534 90)
		(property "Reference" "R399"
			(at -2.667 -0.59563 90)
			(unlocked yes)
			(layer "F.SilkS")
			(effects
				(font
					(size 0.7874 0.5842)
					(thickness 0.1524)
				)
			)
		)
		(property "Value" "VAL*"
			(at 0.02032 2.13233 90)
			(unlocked yes)
			(layer "F.Fab")
			(hide yes)
			(effects
				(font
					(size 0.7874 0.5842)
					(thickness 0.1524)
				)
			)
		)
		(property "Tolerance" "TOL*"
			(at 0.044704 3.05435 90)
			(unlocked yes)
			(layer "Cmts.User")
			(hide yes)
			(effects
				(font
					(size 0.7874 0.5842)
					(thickness 0.1524)
				)
			)
		)
		(property "User Part Number" "PARTNUM*"
			(at 0.02032 4.024884 90)
			(unlocked yes)
			(layer "Cmts.User")
			(hide yes)
			(effects
				(font
					(size 0.7874 0.5842)
					(thickness 0.1524)
				)
			)
		)
		(property "Device Type" "RESISTOR-G155-133R0-01,33OHM,1%"
			(at 0.008382 1.210564 90)
			(unlocked yes)
			(layer "F.Fab")
			(hide yes)
			(effects
				(font
					(size 0.7874 0.5842)
					(thickness 0.1524)
				)
			)
		)
		(duplicate_pad_numbers_are_jumpers no)
		(fp_line
			(start 1.143 -0.5588)
			(end -1.143 -0.5588)
			(stroke
				(width 0.1)
				(type default)
			)
			(layer "F.SilkS")
		)
		(fp_line
			(start -1.143 -0.5588)
			(end -1.143 0.5588)
			(stroke
				(width 0.1)
				(type default)
			)
			(layer "F.SilkS")
		)
		(fp_line
			(start 1.143 0.5588)
			(end 1.143 -0.5588)
			(stroke
				(width 0.1)
				(type default)
			)
			(layer "F.SilkS")
		)
		(fp_line
			(start -1.143 0.5588)
			(end 1.143 0.5588)
			(stroke
				(width 0.1)
				(type default)
			)
			(layer "F.SilkS")
		)
		(fp_rect
			(start -1.143 -0.5588)
			(end 1.143 0.5588)
			(stroke
				(width 0)
				(type default)
			)
			(fill no)
			(layer "F.CrtYd")
		)
		(fp_line
			(start 0.508 -0.3048)
			(end -0.508 -0.3048)
			(stroke
				(width 0.1)
				(type default)
			)
			(layer "F.Fab")
		)
		(fp_line
			(start -0.508 -0.3048)
			(end -0.508 0.3048)
			(stroke
				(width 0.1)
				(type default)
			)
			(layer "F.Fab")
		)
		(fp_line
			(start 0.508 0.3048)
			(end 0.508 -0.3048)
			(stroke
				(width 0.1)
				(type default)
			)
			(layer "F.Fab")
		)
		(fp_line
			(start -0.508 0.3048)
			(end 0.508 0.3048)
			(stroke
				(width 0.1)
				(type default)
			)
			(layer "F.Fab")
		)
		(pad "1" smd rect
			(at -0.5334 0 90)
			(size 0.7112 0.6096)
			(layers "F.Cu" "F.Mask" "F.Paste")
			(net "GPS_SMA_LED_RED_N")
		)
		(pad "2" smd rect
			(at 0.5334 0 90)
			(size 0.7112 0.6096)
			(layers "F.Cu" "F.Mask" "F.Paste")
			(net "UNNAMED_14_LED4PV14_I269_3")
		)
		(zone
			(layer "F.Cu")
			(hatch none 0.5)
			(connect_pads
				(clearance 0)
			)
			(min_thickness 0.25)
			(keepout
				(tracks not_allowed)
				(vias allowed)
				(pads allowed)
				(copperpour not_allowed)
				(footprints allowed)
			)
			(placement
				(enabled no)
				(sheetname "")
			)
			(fill
				(thermal_gap 0.5)
				(thermal_bridge_width 0.5)
				(island_removal_mode 0)
			)
			(polygon
				(pts
					(xy 8.0772 -81.4578) (xy 8.6868 -81.4578) (xy 8.6868 -81.6102) (xy 8.0772 -81.6102)
				)
			)
		)
		(zone
			(layer "F.Cu")
			(hatch none 0.5)
			(connect_pads
				(clearance 0)
			)
			(min_thickness 0.25)
			(keepout
				(tracks allowed)
				(vias not_allowed)
				(pads allowed)
				(copperpour not_allowed)
				(footprints allowed)
			)
			(placement
				(enabled no)
				(sheetname "")
			)
			(fill
				(thermal_gap 0.5)
				(thermal_bridge_width 0.5)
				(island_removal_mode 0)
			)
			(polygon
				(pts
					(xy 8.0772 -81.4578) (xy 8.6868 -81.4578) (xy 8.6868 -81.6102) (xy 8.0772 -81.6102)
				)
			)
		)
	)
)
